#ISCELL
  mstr_symbols cad_note *
  *
#ISCELL
  mstr_symbols design_note *
  *
#ISCELL
  mstr_symbols intel_corp_bpage *
  *
#ISCELL
  mstr_symbols pvccio_cpu0 *
  page96_i1
#ISCELL
  mstr_standard offpage *
  page96_i10
#ISCELL
  mstr_standard offpage *
  page96_i11
#ISCELL
  mstr_standard offpage *
  page96_i14
#ISCELL
  mstr_standard offpage *
  page96_i15
#ISCELL
  mstr_standard offpage *
  page96_i16
#ISCELL
  mstr_standard offpage *
  page96_i17
#CELL
  mstr_discrete res *
  page96_i2
#ISCELL
  mstr_symbols pvccio_cpu1 *
  page96_i24
#CELL
  mstr_discrete res *
  page96_i25
#CELL
  mstr_discrete res *
  page96_i26
#ISCELL
  mstr_symbols pvddq_klm *
  page96_i27
#CELL
  mstr_discrete res *
  page96_i28
#ISCELL
  mstr_symbols pvddq_ghj *
  page96_i29
#CELL
  mstr_discrete res *
  page96_i3
#CELL
  mstr_discrete res *
  page96_i30
#CELL
  mstr_discrete res *
  page96_i36
#ISCELL
  mstr_symbols pvddq_def *
  page96_i4
#ISCELL
  mstr_symbols gnd *
  page96_i41
#CELL
  mstr_digital gtl2014 *
  page96_i42
#ISCELL
  mstr_symbols gnd *
  page96_i45
#CELL
  mstr_digital gtl2014 *
  page96_i46
#CELL
  mstr_discrete res *
  page96_i5
#ISCELL
  mstr_standard offpage *
  page96_i51
#ISCELL
  mstr_standard offpage *
  page96_i52
#ISCELL
  mstr_standard offpage *
  page96_i53
#CELL
  mstr_discrete res *
  page96_i55
#ISCELL
  mstr_standard offpage *
  page96_i59
#ISCELL
  mstr_symbols pvddq_abc *
  page96_i6
#ISCELL
  mstr_standard offpage *
  page96_i60
#ISCELL
  mstr_standard offpage *
  page96_i61
#ISCELL
  mstr_symbols p3v3_stby *
  page96_i65
#ISCELL
  mstr_symbols p3v3_stby *
  page96_i68
#CELL
  mstr_discrete res *
  page96_i69
#CELL
  mstr_discrete res *
  page96_i7
#ISCELL
  mstr_symbols gnd *
  page96_i70
#CELL
  mstr_discrete res *
  page96_i71
#ISCELL
  mstr_symbols gnd *
  page96_i72
#CELL
  dev_discrete cap_a *
  page96_i73
#ISCELL
  mstr_symbols gnd *
  page96_i74
#CELL
  dev_discrete cap_a *
  page96_i75
#ISCELL
  mstr_symbols gnd *
  page96_i76
#ISCELL
  mstr_standard offpage *
  page96_i8
#ISCELL
  mstr_standard offpage *
  page96_i9
